# S9S_MB_2U (Grand Teton) — schematic netlist excerpt (pin names and nets, part order shuffled) for the footprints in the layout excerpt that follows; sources: Cadence DE-HDL packaged netlist, KiCad conversion of 03242023_DA0F0TMBIJ0_F0T_Motherboard_J_brd_V01_OCP.brd

C254  Q_CAP  10UF 6.3V 20% X6S  pkg C0402  page 77 : A = PVCCIN_CPU1 ; B = GND
R4684  Q_RES  0 5% EMPTY  pkg 0402LF  page 305 : A = P12V_HSC_TEMP_ALERT_N ; B = P12V_HSC_TEMP_ALERT_R_N

(kicad_pcb
	(version 20260206)
	(generator "pcbnew")
	(generator_version "10.0")
	(general
		(thickness 1.6)
		(legacy_teardrops no)
	)
	(paper "A4")
	(title_block
		(title "03242023_DA0F0TMBIJ0_F0T_Motherboard_J_brd_V01_OCP.brd")
		(comment 1 "Grand Teton / footprints 1536-1537 of 6105")
	)
	(layers
		(0 "F.Cu" signal "TOP")
		(4 "In1.Cu" signal "GND")
		(6 "In2.Cu" signal "IN1")
		(8 "In3.Cu" signal "GND1")
		(10 "In4.Cu" signal "IN2")
		(12 "In5.Cu" signal "GND2")
		(14 "In6.Cu" signal "IN3")
		(16 "In7.Cu" signal "GND3")
		(18 "In8.Cu" signal "VCC")
		(20 "In9.Cu" signal "VCC1")
		(22 "In10.Cu" signal "GND4")
		(24 "In11.Cu" signal "IN4")
		(26 "In12.Cu" signal "GND5")
		(28 "In13.Cu" signal "IN5")
		(30 "In14.Cu" signal "GND6")
		(32 "In15.Cu" signal "IN6")
		(34 "In16.Cu" signal "GND7")
		(2 "B.Cu" signal "BOTTOM")
		(9 "F.Adhes" user "F.Adhesive")
		(11 "B.Adhes" user "B.Adhesive")
		(13 "F.Paste" user "Package Geometry/Pastemask Top")
		(15 "B.Paste" user "Package Geometry/Pastemask Bottom")
		(5 "F.SilkS" user "Ref Des/Silkscreen Top")
		(7 "B.SilkS" user "Ref Des/Silkscreen Bottom")
		(1 "F.Mask" user "Board Geometry/Soldermask Top")
		(3 "B.Mask" user "Board Geometry/Soldermask Bottom")
		(17 "Dwgs.User" user "User.Drawings")
		(19 "Cmts.User" user "User.Comments")
		(21 "Eco1.User" user "User.Eco1")
		(23 "Eco2.User" user "User.Eco2")
		(25 "Edge.Cuts" user "Board Geometry/Outline")
		(27 "Margin" user)
		(31 "F.CrtYd" user "Package Geometry/Place Bound Top")
		(29 "B.CrtYd" user "Package Geometry/Place Bound Bottom")
		(35 "F.Fab" user "Ref Des/Assembly Top")
		(33 "B.Fab" user "Ref Des/Assembly Bottom")
	)
	(footprint ""
		(layer "F.Cu")
		(at 298.16552 -407.6954)
		(property "Reference" "R4684"
			(at 0 0 0)
			(layer "F.SilkS")
			(hide yes)
			(effects
				(font
					(size 1.27 1.27)
				)
			)
		)
		(property "Value" ""
			(at 0 0 0)
			(layer "F.Fab")
			(effects
				(font
					(size 1.27 1.27)
				)
			)
		)
		(duplicate_pad_numbers_are_jumpers no)
		(fp_line
			(start -0.7874 -0.4064)
			(end 0.7874 -0.4064)
			(stroke
				(width 0.1524)
				(type default)
			)
			(layer "F.SilkS")
		)
		(fp_line
			(start -0.7874 0.4064)
			(end -0.7874 -0.4064)
			(stroke
				(width 0.1524)
				(type default)
			)
			(layer "F.SilkS")
		)
		(fp_line
			(start 0.7874 -0.4064)
			(end 0.7874 0.4064)
			(stroke
				(width 0.1524)
				(type default)
			)
			(layer "F.SilkS")
		)
		(fp_line
			(start 0.7874 0.4064)
			(end -0.7874 0.4064)
			(stroke
				(width 0.1524)
				(type default)
			)
			(layer "F.SilkS")
		)
		(fp_line
			(start -0.67945 -0.305054)
			(end -0.12065 -0.305054)
			(stroke
				(width 0.1)
				(type default)
			)
			(layer "F.Fab")
		)
		(fp_line
			(start -0.67945 0.3048)
			(end -0.67945 -0.305054)
			(stroke
				(width 0.1)
				(type default)
			)
			(layer "F.Fab")
		)
		(fp_line
			(start -0.12065 -0.305054)
			(end -0.12065 -0.2794)
			(stroke
				(width 0.1)
				(type default)
			)
			(layer "F.Fab")
		)
		(fp_line
			(start -0.12065 -0.2794)
			(end 0.12065 -0.2794)
			(stroke
				(width 0.1)
				(type default)
			)
			(layer "F.Fab")
		)
		(fp_line
			(start -0.12065 0.2794)
			(end -0.12065 0.3048)
			(stroke
				(width 0.1)
				(type default)
			)
			(layer "F.Fab")
		)
		(fp_line
			(start -0.12065 0.3048)
			(end -0.67945 0.3048)
			(stroke
				(width 0.1)
				(type default)
			)
			(layer "F.Fab")
		)
		(fp_line
			(start 0.120396 0.2794)
			(end -0.12065 0.2794)
			(stroke
				(width 0.1)
				(type default)
			)
			(layer "F.Fab")
		)
		(fp_line
			(start 0.120396 0.3048)
			(end 0.120396 0.2794)
			(stroke
				(width 0.1)
				(type default)
			)
			(layer "F.Fab")
		)
		(fp_line
			(start 0.12065 -0.3048)
			(end 0.67945 -0.3048)
			(stroke
				(width 0.1)
				(type default)
			)
			(layer "F.Fab")
		)
		(fp_line
			(start 0.12065 -0.2794)
			(end 0.12065 -0.3048)
			(stroke
				(width 0.1)
				(type default)
			)
			(layer "F.Fab")
		)
		(fp_line
			(start 0.67945 -0.3048)
			(end 0.67945 0.3048)
			(stroke
				(width 0.1)
				(type default)
			)
			(layer "F.Fab")
		)
		(fp_line
			(start 0.67945 0.3048)
			(end 0.120396 0.3048)
			(stroke
				(width 0.1)
				(type default)
			)
			(layer "F.Fab")
		)
		(pad "1" smd circle
			(at -0.40005 0)
			(size 0 0)
			(layers "F.Cu" "F.Mask" "F.Paste")
			(net "P12V_HSC_TEMP_ALERT_N")
		)
		(pad "2" smd circle
			(at 0.40005 0)
			(size 0 0)
			(layers "F.Cu" "F.Mask" "F.Paste")
			(net "P12V_HSC_TEMP_ALERT_R_N")
		)
	)
	(footprint ""
		(layer "F.Cu")
		(at 118.542816 -241.97691 -90)
		(property "Reference" "C254"
			(at 0 0 270)
			(layer "F.SilkS")
			(hide yes)
			(effects
				(font
					(size 1.27 1.27)
				)
			)
		)
		(property "Value" ""
			(at 0 0 270)
			(layer "F.Fab")
			(effects
				(font
					(size 1.27 1.27)
				)
			)
		)
		(duplicate_pad_numbers_are_jumpers no)
		(fp_line
			(start -0.7874 0.4064)
			(end -0.7874 -0.4064)
			(stroke
				(width 0.1524)
				(type default)
			)
			(layer "F.SilkS")
		)
		(fp_line
			(start 0.7874 0.4064)
			(end -0.7874 0.4064)
			(stroke
				(width 0.1524)
				(type default)
			)
			(layer "F.SilkS")
		)
		(fp_line
			(start -0.7874 -0.4064)
			(end 0.7874 -0.4064)
			(stroke
				(width 0.1524)
				(type default)
			)
			(layer "F.SilkS")
		)
		(fp_line
			(start 0.7874 -0.4064)
			(end 0.7874 0.4064)
			(stroke
				(width 0.1524)
				(type default)
			)
			(layer "F.SilkS")
		)
		(fp_line
			(start -0.67945 0.3048)
			(end -0.67945 -0.305054)
			(stroke
				(width 0.1)
				(type default)
			)
			(layer "F.Fab")
		)
		(fp_line
			(start -0.12065 0.3048)
			(end -0.67945 0.3048)
			(stroke
				(width 0.1)
				(type default)
			)
			(layer "F.Fab")
		)
		(fp_line
			(start 0.120396 0.3048)
			(end 0.120396 0.2794)
			(stroke
				(width 0.1)
				(type default)
			)
			(layer "F.Fab")
		)
		(fp_line
			(start 0.67945 0.3048)
			(end 0.120396 0.3048)
			(stroke
				(width 0.1)
				(type default)
			)
			(layer "F.Fab")
		)
		(fp_line
			(start -0.12065 0.2794)
			(end -0.12065 0.3048)
			(stroke
				(width 0.1)
				(type default)
			)
			(layer "F.Fab")
		)
		(fp_line
			(start 0.120396 0.2794)
			(end -0.12065 0.2794)
			(stroke
				(width 0.1)
				(type default)
			)
			(layer "F.Fab")
		)
		(fp_line
			(start -0.12065 -0.2794)
			(end 0.12065 -0.2794)
			(stroke
				(width 0.1)
				(type default)
			)
			(layer "F.Fab")
		)
		(fp_line
			(start 0.12065 -0.2794)
			(end 0.12065 -0.3048)
			(stroke
				(width 0.1)
				(type default)
			)
			(layer "F.Fab")
		)
		(fp_line
			(start 0.12065 -0.3048)
			(end 0.67945 -0.3048)
			(stroke
				(width 0.1)
				(type default)
			)
			(layer "F.Fab")
		)
		(fp_line
			(start 0.67945 -0.3048)
			(end 0.67945 0.3048)
			(stroke
				(width 0.1)
				(type default)
			)
			(layer "F.Fab")
		)
		(fp_line
			(start -0.67945 -0.305054)
			(end -0.12065 -0.305054)
			(stroke
				(width 0.1)
				(type default)
			)
			(layer "F.Fab")
		)
		(fp_line
			(start -0.12065 -0.305054)
			(end -0.12065 -0.2794)
			(stroke
				(width 0.1)
				(type default)
			)
			(layer "F.Fab")
		)
		(pad "1" smd circle
			(at -0.40005 0 270)
			(size 0 0)
			(layers "F.Cu" "F.Mask" "F.Paste")
			(net "PVCCIN_CPU1")
		)
		(pad "2" smd circle
			(at 0.40005 0 270)
			(size 0 0)
			(layers "F.Cu" "F.Mask" "F.Paste")
			(net "GND")
		)
	)
)
